(kicad_pcb
	(version 20260206)
	(generator "pcbnew")
	(generator_version "10.0")
	(general
		(thickness 1.6)
		(legacy_teardrops no)
	)
	(paper "A4")
	(title_block
		(title "03242023_DA0F0TMBIJ0_F0T_Motherboard_J_brd_V01_OCP.brd")
		(comment 1 "Grand Teton / footprint 2126 of 6105 (J112), pads 76-90 of 90")
	)
	(layers
		(0 "F.Cu" signal "TOP")
		(4 "In1.Cu" signal "GND")
		(6 "In2.Cu" signal "IN1")
		(8 "In3.Cu" signal "GND1")
		(10 "In4.Cu" signal "IN2")
		(12 "In5.Cu" signal "GND2")
		(14 "In6.Cu" signal "IN3")
		(16 "In7.Cu" signal "GND3")
		(18 "In8.Cu" signal "VCC")
		(20 "In9.Cu" signal "VCC1")
		(22 "In10.Cu" signal "GND4")
		(24 "In11.Cu" signal "IN4")
		(26 "In12.Cu" signal "GND5")
		(28 "In13.Cu" signal "IN5")
		(30 "In14.Cu" signal "GND6")
		(32 "In15.Cu" signal "IN6")
		(34 "In16.Cu" signal "GND7")
		(2 "B.Cu" signal "BOTTOM")
		(9 "F.Adhes" user "F.Adhesive")
		(11 "B.Adhes" user "B.Adhesive")
		(13 "F.Paste" user "Package Geometry/Pastemask Top")
		(15 "B.Paste" user "Package Geometry/Pastemask Bottom")
		(5 "F.SilkS" user "Ref Des/Silkscreen Top")
		(7 "B.SilkS" user "Ref Des/Silkscreen Bottom")
		(1 "F.Mask" user "Board Geometry/Soldermask Top")
		(3 "B.Mask" user "Board Geometry/Soldermask Bottom")
		(17 "Dwgs.User" user "User.Drawings")
		(19 "Cmts.User" user "User.Comments")
		(21 "Eco1.User" user "User.Eco1")
		(23 "Eco2.User" user "User.Eco2")
		(25 "Edge.Cuts" user "Board Geometry/Outline")
		(27 "Margin" user)
		(31 "F.CrtYd" user "Package Geometry/Place Bound Top")
		(29 "B.CrtYd" user "Package Geometry/Place Bound Bottom")
		(35 "F.Fab" user "Ref Des/Assembly Top")
		(33 "B.Fab" user "Ref Des/Assembly Bottom")
	)
	(footprint ""
		(layer "F.Cu")
		(at 58.650124 -440.489848)
		(property "Reference" "J112"
			(at -7.9883 9.742932 0)
			(unlocked yes)
			(layer "F.SilkS")
			(effects
				(font
					(size 0.7874 0.5842)
					(thickness 0.1524)
				)
				(justify left)
			)
		)
		(property "Value" ""
			(at 0 0 0)
			(layer "F.Fab")
			(effects
				(font
					(size 1.27 1.27)
				)
			)
		)
		(duplicate_pad_numbers_are_jumpers no)
		(pad "S2" thru_hole circle
			(at 1.999996 21.800058 180)
			(size 0.906272 0.906272)
			(drill 0.499872)
			(layers "*.Cu" "*.Mask")
			(remove_unused_layers no)
			(net "GND")
			(clearance 0.0508)
			(thermal_gap 0.0508)
		)
		(pad "S3" thru_hole circle
			(at 3.999992 21.599906 180)
			(size 0.766318 0.766318)
			(drill 0.359918)
			(layers "*.Cu" "*.Mask")
			(remove_unused_layers no)
			(net "SMB_2_BMC_GPU_BUF_SDA")
			(clearance 0.0508)
			(thermal_gap 0.0508)
		)
		(pad "S4" thru_hole circle
			(at 5.999988 21.800058 180)
			(size 0.906272 0.906272)
			(drill 0.499872)
			(layers "*.Cu" "*.Mask")
			(remove_unused_layers no)
			(net "GND")
			(clearance 0.0508)
			(thermal_gap 0.0508)
		)
		(pad "S5" thru_hole circle
			(at 7.999984 21.599906 180)
			(size 0.766318 0.766318)
			(drill 0.359918)
			(layers "*.Cu" "*.Mask")
			(remove_unused_layers no)
			(net "NC_J112_S5")
			(clearance 0.0508)
			(thermal_gap 0.0508)
		)
		(pad "S6" thru_hole circle
			(at 9.99998 21.800058 180)
			(size 0.906272 0.906272)
			(drill 0.499872)
			(layers "*.Cu" "*.Mask")
			(remove_unused_layers no)
			(net "GND")
			(clearance 0.0508)
			(thermal_gap 0.0508)
		)
		(pad "S7" thru_hole circle
			(at 11.999976 21.599906 180)
			(size 0.766318 0.766318)
			(drill 0.359918)
			(layers "*.Cu" "*.Mask")
			(remove_unused_layers no)
			(net "P3E_PCH_NVS_TX_C_DP<1>")
			(clearance 0.0508)
			(thermal_gap 0.0508)
		)
		(pad "S8" thru_hole circle
			(at 13.999972 21.800058 180)
			(size 0.906272 0.906272)
			(drill 0.499872)
			(layers "*.Cu" "*.Mask")
			(remove_unused_layers no)
			(net "GND")
			(clearance 0.0508)
			(thermal_gap 0.0508)
		)
		(pad "T1" thru_hole circle
			(at 0 22.800056 180)
			(size 0.906272 0.906272)
			(drill 0.499872)
			(layers "*.Cu" "*.Mask")
			(remove_unused_layers no)
			(net "GND")
			(clearance 0.0508)
			(thermal_gap 0.0508)
		)
		(pad "T2" thru_hole circle
			(at 1.999996 22.999954 180)
			(size 0.766318 0.766318)
			(drill 0.359918)
			(layers "*.Cu" "*.Mask")
			(remove_unused_layers no)
			(net "GPU_FPGA_READY")
			(clearance 0.0508)
			(thermal_gap 0.0508)
		)
		(pad "T3" thru_hole circle
			(at 3.999992 22.800056 180)
			(size 0.906272 0.906272)
			(drill 0.499872)
			(layers "*.Cu" "*.Mask")
			(remove_unused_layers no)
			(net "GND")
			(clearance 0.0508)
			(thermal_gap 0.0508)
		)
		(pad "T4" thru_hole circle
			(at 5.999988 22.999954 180)
			(size 0.766318 0.766318)
			(drill 0.359918)
			(layers "*.Cu" "*.Mask")
			(remove_unused_layers no)
			(net "GPU_NVS_PWR_BRAKE_N_BUF")
			(clearance 0.0508)
			(thermal_gap 0.0508)
		)
		(pad "T5" thru_hole circle
			(at 7.999984 22.800056 180)
			(size 0.906272 0.906272)
			(drill 0.499872)
			(layers "*.Cu" "*.Mask")
			(remove_unused_layers no)
			(net "GND")
			(clearance 0.0508)
			(thermal_gap 0.0508)
		)
		(pad "T6" thru_hole circle
			(at 9.99998 22.999954 180)
			(size 0.766318 0.766318)
			(drill 0.359918)
			(layers "*.Cu" "*.Mask")
			(remove_unused_layers no)
			(net "GPU_FPGA_THERM_OVERT_N")
			(clearance 0.0508)
			(thermal_gap 0.0508)
		)
		(pad "T7" thru_hole circle
			(at 11.999976 22.800056 180)
			(size 0.906272 0.906272)
			(drill 0.499872)
			(layers "*.Cu" "*.Mask")
			(remove_unused_layers no)
			(net "GND")
			(clearance 0.0508)
			(thermal_gap 0.0508)
		)
		(pad "T8" thru_hole circle
			(at 13.999972 22.999954 180)
			(size 0.766318 0.766318)
			(drill 0.359918)
			(layers "*.Cu" "*.Mask")
			(remove_unused_layers no)
			(net "RST_PERST_0_SWB_BUF_N")
			(clearance 0.0508)
			(thermal_gap 0.0508)
		)
	)
)
